(kicad_pcb
	(version 20260206)
	(generator "pcbnew")
	(generator_version "10.0")
	(general
		(thickness 1.6)
		(legacy_teardrops no)
	)
	(paper "A4")
	(title_block
		(title "03242023_DA0F0TMBIJ0_F0T_Motherboard_J_brd_V01_OCP.brd")
		(comment 1 "Grand Teton / footprints 4547-4552 of 6105")
	)
	(layers
		(0 "F.Cu" signal "TOP")
		(4 "In1.Cu" signal "GND")
		(6 "In2.Cu" signal "IN1")
		(8 "In3.Cu" signal "GND1")
		(10 "In4.Cu" signal "IN2")
		(12 "In5.Cu" signal "GND2")
		(14 "In6.Cu" signal "IN3")
		(16 "In7.Cu" signal "GND3")
		(18 "In8.Cu" signal "VCC")
		(20 "In9.Cu" signal "VCC1")
		(22 "In10.Cu" signal "GND4")
		(24 "In11.Cu" signal "IN4")
		(26 "In12.Cu" signal "GND5")
		(28 "In13.Cu" signal "IN5")
		(30 "In14.Cu" signal "GND6")
		(32 "In15.Cu" signal "IN6")
		(34 "In16.Cu" signal "GND7")
		(2 "B.Cu" signal "BOTTOM")
		(9 "F.Adhes" user "F.Adhesive")
		(11 "B.Adhes" user "B.Adhesive")
		(13 "F.Paste" user "Package Geometry/Pastemask Top")
		(15 "B.Paste" user "Package Geometry/Pastemask Bottom")
		(5 "F.SilkS" user "Ref Des/Silkscreen Top")
		(7 "B.SilkS" user "Ref Des/Silkscreen Bottom")
		(1 "F.Mask" user "Board Geometry/Soldermask Top")
		(3 "B.Mask" user "Board Geometry/Soldermask Bottom")
		(17 "Dwgs.User" user "User.Drawings")
		(19 "Cmts.User" user "User.Comments")
		(21 "Eco1.User" user "User.Eco1")
		(23 "Eco2.User" user "User.Eco2")
		(25 "Edge.Cuts" user "Board Geometry/Outline")
		(27 "Margin" user)
		(31 "F.CrtYd" user "Package Geometry/Place Bound Top")
		(29 "B.CrtYd" user "Package Geometry/Place Bound Bottom")
		(35 "F.Fab" user "Ref Des/Assembly Top")
		(33 "B.Fab" user "Ref Des/Assembly Bottom")
	)
	(footprint ""
		(layer "B.Cu")
		(at 446.966848 -184.060592 180)
		(property "Reference" "C1363"
			(at 0 0 0)
			(layer "B.SilkS")
			(hide yes)
			(effects
				(font
					(size 1.27 1.27)
				)
				(justify mirror)
			)
		)
		(property "Value" ""
			(at 0 0 0)
			(layer "B.Fab")
			(effects
				(font
					(size 1.27 1.27)
				)
				(justify mirror)
			)
		)
		(duplicate_pad_numbers_are_jumpers no)
		(fp_line
			(start 0.7874 0.4064)
			(end 0.7874 -0.4064)
			(stroke
				(width 0.1524)
				(type default)
			)
			(layer "B.SilkS")
		)
		(fp_line
			(start 0.7874 -0.4064)
			(end -0.7874 -0.4064)
			(stroke
				(width 0.1524)
				(type default)
			)
			(layer "B.SilkS")
		)
		(fp_line
			(start -0.7874 0.4064)
			(end 0.7874 0.4064)
			(stroke
				(width 0.1524)
				(type default)
			)
			(layer "B.SilkS")
		)
		(fp_line
			(start -0.7874 -0.4064)
			(end -0.7874 0.4064)
			(stroke
				(width 0.1524)
				(type default)
			)
			(layer "B.SilkS")
		)
		(fp_line
			(start 0.67945 0.3048)
			(end 0.67945 -0.305054)
			(stroke
				(width 0.1)
				(type default)
			)
			(layer "B.Fab")
		)
		(fp_line
			(start 0.67945 -0.305054)
			(end 0.12065 -0.305054)
			(stroke
				(width 0.1)
				(type default)
			)
			(layer "B.Fab")
		)
		(fp_line
			(start 0.12065 0.3048)
			(end 0.67945 0.3048)
			(stroke
				(width 0.1)
				(type default)
			)
			(layer "B.Fab")
		)
		(fp_line
			(start 0.12065 0.2794)
			(end 0.12065 0.3048)
			(stroke
				(width 0.1)
				(type default)
			)
			(layer "B.Fab")
		)
		(fp_line
			(start 0.12065 -0.2794)
			(end -0.12065 -0.2794)
			(stroke
				(width 0.1)
				(type default)
			)
			(layer "B.Fab")
		)
		(fp_line
			(start 0.12065 -0.305054)
			(end 0.12065 -0.2794)
			(stroke
				(width 0.1)
				(type default)
			)
			(layer "B.Fab")
		)
		(fp_line
			(start -0.120396 0.3048)
			(end -0.120396 0.2794)
			(stroke
				(width 0.1)
				(type default)
			)
			(layer "B.Fab")
		)
		(fp_line
			(start -0.120396 0.2794)
			(end 0.12065 0.2794)
			(stroke
				(width 0.1)
				(type default)
			)
			(layer "B.Fab")
		)
		(fp_line
			(start -0.12065 -0.2794)
			(end -0.12065 -0.3048)
			(stroke
				(width 0.1)
				(type default)
			)
			(layer "B.Fab")
		)
		(fp_line
			(start -0.12065 -0.3048)
			(end -0.67945 -0.3048)
			(stroke
				(width 0.1)
				(type default)
			)
			(layer "B.Fab")
		)
		(fp_line
			(start -0.67945 0.3048)
			(end -0.120396 0.3048)
			(stroke
				(width 0.1)
				(type default)
			)
			(layer "B.Fab")
		)
		(fp_line
			(start -0.67945 -0.3048)
			(end -0.67945 0.3048)
			(stroke
				(width 0.1)
				(type default)
			)
			(layer "B.Fab")
		)
		(pad "1" smd circle
			(at 0.40005 0)
			(size 0 0)
			(layers "B.Cu" "B.Mask" "B.Paste")
			(net "PVNN_MAIN_CPU0")
		)
		(pad "2" smd circle
			(at -0.40005 0)
			(size 0 0)
			(layers "B.Cu" "B.Mask" "B.Paste")
			(net "GND")
		)
	)
	(footprint ""
		(layer "B.Cu")
		(at 414.41243 -316.621922 90)
		(property "Reference" "R3883"
			(at 0 0 90)
			(layer "B.SilkS")
			(hide yes)
			(effects
				(font
					(size 1.27 1.27)
				)
				(justify mirror)
			)
		)
		(property "Value" ""
			(at 0 0 90)
			(layer "B.Fab")
			(effects
				(font
					(size 1.27 1.27)
				)
				(justify mirror)
			)
		)
		(duplicate_pad_numbers_are_jumpers no)
		(fp_line
			(start 0.7874 -0.4064)
			(end -0.7874 -0.4064)
			(stroke
				(width 0.1524)
				(type default)
			)
			(layer "B.SilkS")
		)
		(fp_line
			(start -0.7874 -0.4064)
			(end -0.7874 0.4064)
			(stroke
				(width 0.1524)
				(type default)
			)
			(layer "B.SilkS")
		)
		(fp_line
			(start 0.7874 0.4064)
			(end 0.7874 -0.4064)
			(stroke
				(width 0.1524)
				(type default)
			)
			(layer "B.SilkS")
		)
		(fp_line
			(start -0.7874 0.4064)
			(end 0.7874 0.4064)
			(stroke
				(width 0.1524)
				(type default)
			)
			(layer "B.SilkS")
		)
		(fp_line
			(start 0.67945 -0.305054)
			(end 0.12065 -0.305054)
			(stroke
				(width 0.1)
				(type default)
			)
			(layer "B.Fab")
		)
		(fp_line
			(start 0.12065 -0.305054)
			(end 0.12065 -0.2794)
			(stroke
				(width 0.1)
				(type default)
			)
			(layer "B.Fab")
		)
		(fp_line
			(start -0.12065 -0.3048)
			(end -0.67945 -0.3048)
			(stroke
				(width 0.1)
				(type default)
			)
			(layer "B.Fab")
		)
		(fp_line
			(start -0.67945 -0.3048)
			(end -0.67945 0.3048)
			(stroke
				(width 0.1)
				(type default)
			)
			(layer "B.Fab")
		)
		(fp_line
			(start 0.12065 -0.2794)
			(end -0.12065 -0.2794)
			(stroke
				(width 0.1)
				(type default)
			)
			(layer "B.Fab")
		)
		(fp_line
			(start -0.12065 -0.2794)
			(end -0.12065 -0.3048)
			(stroke
				(width 0.1)
				(type default)
			)
			(layer "B.Fab")
		)
		(fp_line
			(start 0.12065 0.2794)
			(end 0.12065 0.3048)
			(stroke
				(width 0.1)
				(type default)
			)
			(layer "B.Fab")
		)
		(fp_line
			(start -0.120396 0.2794)
			(end 0.12065 0.2794)
			(stroke
				(width 0.1)
				(type default)
			)
			(layer "B.Fab")
		)
		(fp_line
			(start 0.67945 0.3048)
			(end 0.67945 -0.305054)
			(stroke
				(width 0.1)
				(type default)
			)
			(layer "B.Fab")
		)
		(fp_line
			(start 0.12065 0.3048)
			(end 0.67945 0.3048)
			(stroke
				(width 0.1)
				(type default)
			)
			(layer "B.Fab")
		)
		(fp_line
			(start -0.120396 0.3048)
			(end -0.120396 0.2794)
			(stroke
				(width 0.1)
				(type default)
			)
			(layer "B.Fab")
		)
		(fp_line
			(start -0.67945 0.3048)
			(end -0.120396 0.3048)
			(stroke
				(width 0.1)
				(type default)
			)
			(layer "B.Fab")
		)
		(pad "1" smd circle
			(at 0.40005 0 270)
			(size 0 0)
			(layers "B.Cu" "B.Mask" "B.Paste")
			(net "I3C_SPD_DDREFGH_CPU0_LVC1_SCL_R")
		)
		(pad "2" smd circle
			(at -0.40005 0 270)
			(size 0 0)
			(layers "B.Cu" "B.Mask" "B.Paste")
			(net "I3C_SPD_DDREFGH_CPU0_LVC1_SCL")
		)
	)
	(footprint ""
		(layer "B.Cu")
		(at 334.59674 -49.022508)
		(property "Reference" "C1189"
			(at 0 0 0)
			(layer "B.SilkS")
			(hide yes)
			(effects
				(font
					(size 1.27 1.27)
				)
				(justify mirror)
			)
		)
		(property "Value" ""
			(at 0 0 0)
			(layer "B.Fab")
			(effects
				(font
					(size 1.27 1.27)
				)
				(justify mirror)
			)
		)
		(duplicate_pad_numbers_are_jumpers no)
		(fp_line
			(start -0.7874 -0.4064)
			(end -0.7874 0.4064)
			(stroke
				(width 0.1524)
				(type default)
			)
			(layer "B.SilkS")
		)
		(fp_line
			(start -0.7874 0.4064)
			(end 0.7874 0.4064)
			(stroke
				(width 0.1524)
				(type default)
			)
			(layer "B.SilkS")
		)
		(fp_line
			(start 0.7874 -0.4064)
			(end -0.7874 -0.4064)
			(stroke
				(width 0.1524)
				(type default)
			)
			(layer "B.SilkS")
		)
		(fp_line
			(start 0.7874 0.4064)
			(end 0.7874 -0.4064)
			(stroke
				(width 0.1524)
				(type default)
			)
			(layer "B.SilkS")
		)
		(fp_line
			(start -0.67945 -0.3048)
			(end -0.67945 0.3048)
			(stroke
				(width 0.1)
				(type default)
			)
			(layer "B.Fab")
		)
		(fp_line
			(start -0.67945 0.3048)
			(end -0.120396 0.3048)
			(stroke
				(width 0.1)
				(type default)
			)
			(layer "B.Fab")
		)
		(fp_line
			(start -0.12065 -0.3048)
			(end -0.67945 -0.3048)
			(stroke
				(width 0.1)
				(type default)
			)
			(layer "B.Fab")
		)
		(fp_line
			(start -0.12065 -0.2794)
			(end -0.12065 -0.3048)
			(stroke
				(width 0.1)
				(type default)
			)
			(layer "B.Fab")
		)
		(fp_line
			(start -0.120396 0.2794)
			(end 0.12065 0.2794)
			(stroke
				(width 0.1)
				(type default)
			)
			(layer "B.Fab")
		)
		(fp_line
			(start -0.120396 0.3048)
			(end -0.120396 0.2794)
			(stroke
				(width 0.1)
				(type default)
			)
			(layer "B.Fab")
		)
		(fp_line
			(start 0.12065 -0.305054)
			(end 0.12065 -0.2794)
			(stroke
				(width 0.1)
				(type default)
			)
			(layer "B.Fab")
		)
		(fp_line
			(start 0.12065 -0.2794)
			(end -0.12065 -0.2794)
			(stroke
				(width 0.1)
				(type default)
			)
			(layer "B.Fab")
		)
		(fp_line
			(start 0.12065 0.2794)
			(end 0.12065 0.3048)
			(stroke
				(width 0.1)
				(type default)
			)
			(layer "B.Fab")
		)
		(fp_line
			(start 0.12065 0.3048)
			(end 0.67945 0.3048)
			(stroke
				(width 0.1)
				(type default)
			)
			(layer "B.Fab")
		)
		(fp_line
			(start 0.67945 -0.305054)
			(end 0.12065 -0.305054)
			(stroke
				(width 0.1)
				(type default)
			)
			(layer "B.Fab")
		)
		(fp_line
			(start 0.67945 0.3048)
			(end 0.67945 -0.305054)
			(stroke
				(width 0.1)
				(type default)
			)
			(layer "B.Fab")
		)
		(pad "1" smd circle
			(at 0.40005 0 180)
			(size 0 0)
			(layers "B.Cu" "B.Mask" "B.Paste")
			(net "P1V05_PCH_AUX")
		)
		(pad "2" smd circle
			(at -0.40005 0 180)
			(size 0 0)
			(layers "B.Cu" "B.Mask" "B.Paste")
			(net "GND")
		)
	)
	(footprint ""
		(layer "B.Cu")
		(at 192.280286 -193.615056 -90)
		(property "Reference" "R702"
			(at 0 0 90)
			(layer "B.SilkS")
			(hide yes)
			(effects
				(font
					(size 1.27 1.27)
				)
				(justify mirror)
			)
		)
		(property "Value" ""
			(at 0 0 90)
			(layer "B.Fab")
			(effects
				(font
					(size 1.27 1.27)
				)
				(justify mirror)
			)
		)
		(duplicate_pad_numbers_are_jumpers no)
		(fp_line
			(start -0.7874 0.4064)
			(end 0.7874 0.4064)
			(stroke
				(width 0.1524)
				(type default)
			)
			(layer "B.SilkS")
		)
		(fp_line
			(start 0.7874 0.4064)
			(end 0.7874 -0.4064)
			(stroke
				(width 0.1524)
				(type default)
			)
			(layer "B.SilkS")
		)
		(fp_line
			(start -0.7874 -0.4064)
			(end -0.7874 0.4064)
			(stroke
				(width 0.1524)
				(type default)
			)
			(layer "B.SilkS")
		)
		(fp_line
			(start 0.7874 -0.4064)
			(end -0.7874 -0.4064)
			(stroke
				(width 0.1524)
				(type default)
			)
			(layer "B.SilkS")
		)
		(fp_line
			(start -0.67945 0.3048)
			(end -0.120396 0.3048)
			(stroke
				(width 0.1)
				(type default)
			)
			(layer "B.Fab")
		)
		(fp_line
			(start -0.120396 0.3048)
			(end -0.120396 0.2794)
			(stroke
				(width 0.1)
				(type default)
			)
			(layer "B.Fab")
		)
		(fp_line
			(start 0.12065 0.3048)
			(end 0.67945 0.3048)
			(stroke
				(width 0.1)
				(type default)
			)
			(layer "B.Fab")
		)
		(fp_line
			(start 0.67945 0.3048)
			(end 0.67945 -0.305054)
			(stroke
				(width 0.1)
				(type default)
			)
			(layer "B.Fab")
		)
		(fp_line
			(start -0.120396 0.2794)
			(end 0.12065 0.2794)
			(stroke
				(width 0.1)
				(type default)
			)
			(layer "B.Fab")
		)
		(fp_line
			(start 0.12065 0.2794)
			(end 0.12065 0.3048)
			(stroke
				(width 0.1)
				(type default)
			)
			(layer "B.Fab")
		)
		(fp_line
			(start -0.12065 -0.2794)
			(end -0.12065 -0.3048)
			(stroke
				(width 0.1)
				(type default)
			)
			(layer "B.Fab")
		)
		(fp_line
			(start 0.12065 -0.2794)
			(end -0.12065 -0.2794)
			(stroke
				(width 0.1)
				(type default)
			)
			(layer "B.Fab")
		)
		(fp_line
			(start -0.67945 -0.3048)
			(end -0.67945 0.3048)
			(stroke
				(width 0.1)
				(type default)
			)
			(layer "B.Fab")
		)
		(fp_line
			(start -0.12065 -0.3048)
			(end -0.67945 -0.3048)
			(stroke
				(width 0.1)
				(type default)
			)
			(layer "B.Fab")
		)
		(fp_line
			(start 0.12065 -0.305054)
			(end 0.12065 -0.2794)
			(stroke
				(width 0.1)
				(type default)
			)
			(layer "B.Fab")
		)
		(fp_line
			(start 0.67945 -0.305054)
			(end 0.12065 -0.305054)
			(stroke
				(width 0.1)
				(type default)
			)
			(layer "B.Fab")
		)
		(pad "1" smd circle
			(at 0.40005 0 90)
			(size 0 0)
			(layers "B.Cu" "B.Mask" "B.Paste")
			(net "RST_PLD_CPU1_DRAM_GH_N")
		)
		(pad "2" smd circle
			(at -0.40005 0 90)
			(size 0 0)
			(layers "B.Cu" "B.Mask" "B.Paste")
			(net "GND")
		)
	)
	(footprint ""
		(layer "B.Cu")
		(at 282.788614 -321.549776 -90)
		(property "Reference" "C18"
			(at 0 0 90)
			(layer "B.SilkS")
			(hide yes)
			(effects
				(font
					(size 1.27 1.27)
				)
				(justify mirror)
			)
		)
		(property "Value" ""
			(at 0 0 90)
			(layer "B.Fab")
			(effects
				(font
					(size 1.27 1.27)
				)
				(justify mirror)
			)
		)
		(duplicate_pad_numbers_are_jumpers no)
		(fp_line
			(start -1.524 0.762)
			(end 1.524 0.762)
			(stroke
				(width 0.1524)
				(type default)
			)
			(layer "B.SilkS")
		)
		(fp_line
			(start 1.524 0.762)
			(end 1.524 -0.762)
			(stroke
				(width 0.1524)
				(type default)
			)
			(layer "B.SilkS")
		)
		(fp_line
			(start -1.524 -0.762)
			(end -1.524 0.762)
			(stroke
				(width 0.1524)
				(type default)
			)
			(layer "B.SilkS")
		)
		(fp_line
			(start 1.524 -0.762)
			(end -1.524 -0.762)
			(stroke
				(width 0.1524)
				(type default)
			)
			(layer "B.SilkS")
		)
		(fp_line
			(start -1.1049 0.724916)
			(end -1.1049 -0.724916)
			(stroke
				(width 0.1)
				(type default)
			)
			(layer "B.Fab")
		)
		(fp_line
			(start 1.1049 0.724916)
			(end -1.1049 0.724916)
			(stroke
				(width 0.1)
				(type default)
			)
			(layer "B.Fab")
		)
		(fp_line
			(start -1.1049 -0.724916)
			(end 1.1049 -0.724916)
			(stroke
				(width 0.1)
				(type default)
			)
			(layer "B.Fab")
		)
		(fp_line
			(start 1.1049 -0.724916)
			(end 1.1049 0.724916)
			(stroke
				(width 0.1)
				(type default)
			)
			(layer "B.Fab")
		)
		(pad "1" smd rect
			(at 0.889 0 270)
			(size 1.016 1.27)
			(layers "B.Cu" "B.Mask" "B.Paste")
			(net "P12V_S3_AUX_CPU0_NVDIMM")
		)
		(pad "2" smd rect
			(at -0.889 0 270)
			(size 1.016 1.27)
			(layers "B.Cu" "B.Mask" "B.Paste")
			(net "GND")
		)
	)
	(footprint ""
		(layer "B.Cu")
		(at 334.62849 -50.314352)
		(property "Reference" "C1253"
			(at 0 0 0)
			(layer "B.SilkS")
			(hide yes)
			(effects
				(font
					(size 1.27 1.27)
				)
				(justify mirror)
			)
		)
		(property "Value" ""
			(at 0 0 0)
			(layer "B.Fab")
			(effects
				(font
					(size 1.27 1.27)
				)
				(justify mirror)
			)
		)
		(duplicate_pad_numbers_are_jumpers no)
		(fp_line
			(start -0.7874 -0.4064)
			(end -0.7874 0.4064)
			(stroke
				(width 0.1524)
				(type default)
			)
			(layer "B.SilkS")
		)
		(fp_line
			(start -0.7874 0.4064)
			(end 0.7874 0.4064)
			(stroke
				(width 0.1524)
				(type default)
			)
			(layer "B.SilkS")
		)
		(fp_line
			(start 0.7874 -0.4064)
			(end -0.7874 -0.4064)
			(stroke
				(width 0.1524)
				(type default)
			)
			(layer "B.SilkS")
		)
		(fp_line
			(start 0.7874 0.4064)
			(end 0.7874 -0.4064)
			(stroke
				(width 0.1524)
				(type default)
			)
			(layer "B.SilkS")
		)
		(fp_line
			(start -0.67945 -0.3048)
			(end -0.67945 0.3048)
			(stroke
				(width 0.1)
				(type default)
			)
			(layer "B.Fab")
		)
		(fp_line
			(start -0.67945 0.3048)
			(end -0.120396 0.3048)
			(stroke
				(width 0.1)
				(type default)
			)
			(layer "B.Fab")
		)
		(fp_line
			(start -0.12065 -0.3048)
			(end -0.67945 -0.3048)
			(stroke
				(width 0.1)
				(type default)
			)
			(layer "B.Fab")
		)
		(fp_line
			(start -0.12065 -0.2794)
			(end -0.12065 -0.3048)
			(stroke
				(width 0.1)
				(type default)
			)
			(layer "B.Fab")
		)
		(fp_line
			(start -0.120396 0.2794)
			(end 0.12065 0.2794)
			(stroke
				(width 0.1)
				(type default)
			)
			(layer "B.Fab")
		)
		(fp_line
			(start -0.120396 0.3048)
			(end -0.120396 0.2794)
			(stroke
				(width 0.1)
				(type default)
			)
			(layer "B.Fab")
		)
		(fp_line
			(start 0.12065 -0.305054)
			(end 0.12065 -0.2794)
			(stroke
				(width 0.1)
				(type default)
			)
			(layer "B.Fab")
		)
		(fp_line
			(start 0.12065 -0.2794)
			(end -0.12065 -0.2794)
			(stroke
				(width 0.1)
				(type default)
			)
			(layer "B.Fab")
		)
		(fp_line
			(start 0.12065 0.2794)
			(end 0.12065 0.3048)
			(stroke
				(width 0.1)
				(type default)
			)
			(layer "B.Fab")
		)
		(fp_line
			(start 0.12065 0.3048)
			(end 0.67945 0.3048)
			(stroke
				(width 0.1)
				(type default)
			)
			(layer "B.Fab")
		)
		(fp_line
			(start 0.67945 -0.305054)
			(end 0.12065 -0.305054)
			(stroke
				(width 0.1)
				(type default)
			)
			(layer "B.Fab")
		)
		(fp_line
			(start 0.67945 0.3048)
			(end 0.67945 -0.305054)
			(stroke
				(width 0.1)
				(type default)
			)
			(layer "B.Fab")
		)
		(pad "1" smd circle
			(at 0.40005 0 180)
			(size 0 0)
			(layers "B.Cu" "B.Mask" "B.Paste")
			(net "P1V8_PCH_AUX")
		)
		(pad "2" smd circle
			(at -0.40005 0 180)
			(size 0 0)
			(layers "B.Cu" "B.Mask" "B.Paste")
			(net "GND")
		)
	)
)
